(kicad_pcb
	(version 20260206)
	(generator "pcbnew")
	(generator_version "10.0")
	(general
		(thickness 1.6)
		(legacy_teardrops no)
	)
	(paper "A4")
	(title_block
		(title "Wiwynn_Tioga_Pass_MB.brd")
		(comment 1 "Tioga Pass / footprints 1776-1780 of 4770")
	)
	(layers
		(0 "F.Cu" signal "TOP")
		(4 "In1.Cu" signal "L2GND")
		(6 "In2.Cu" signal "L3")
		(8 "In3.Cu" signal "L4GND")
		(10 "In4.Cu" signal "L5")
		(12 "In5.Cu" signal "L6GND")
		(14 "In6.Cu" signal "L7VCC")
		(16 "In7.Cu" signal "L8VCC")
		(18 "In8.Cu" signal "L9GND")
		(20 "In9.Cu" signal "L10")
		(22 "In10.Cu" signal "L11GND")
		(24 "In11.Cu" signal "L12")
		(26 "In12.Cu" signal "L13GND")
		(2 "B.Cu" signal "BOTTOM")
		(9 "F.Adhes" user "F.Adhesive")
		(11 "B.Adhes" user "B.Adhesive")
		(13 "F.Paste" user "Package Geometry/Pastemask Top")
		(15 "B.Paste" user "Package Geometry/Pastemask Bottom")
		(5 "F.SilkS" user "Ref Des/Silkscreen Top")
		(7 "B.SilkS" user "Ref Des/Silkscreen Bottom")
		(1 "F.Mask" user "Board Geometry/Soldermask Top")
		(3 "B.Mask" user "Board Geometry/Soldermask Bottom")
		(17 "Dwgs.User" user "User.Drawings")
		(19 "Cmts.User" user "User.Comments")
		(21 "Eco1.User" user "User.Eco1")
		(23 "Eco2.User" user "User.Eco2")
		(25 "Edge.Cuts" user "Board Geometry/Outline")
		(27 "Margin" user)
		(31 "F.CrtYd" user "Package Geometry/Place Bound Top")
		(29 "B.CrtYd" user "Package Geometry/Place Bound Bottom")
		(35 "F.Fab" user "Ref Des/Assembly Top")
		(33 "B.Fab" user "Ref Des/Assembly Bottom")
	)
	(footprint ""
		(layer "F.Cu")
		(at 499.872 -149.86)
		(property "Reference" "DS9A2"
			(at -1.31953 -0.28448 90)
			(unlocked yes)
			(layer "F.SilkS")
			(effects
				(font
					(size 0.7874 0.5842)
					(thickness 0.1524)
				)
			)
		)
		(property "Value" ""
			(at 0 0 0)
			(layer "F.Fab")
			(effects
				(font
					(size 1.27 1.27)
				)
			)
		)
		(duplicate_pad_numbers_are_jumpers no)
		(fp_line
			(start -1.842262 1.00711)
			(end -1.36144 0.174244)
			(stroke
				(width 0.1524)
				(type default)
			)
			(layer "F.SilkS")
		)
		(fp_line
			(start -1.36144 -0.949198)
			(end -1.36144 0.174244)
			(stroke
				(width 0.1524)
				(type default)
			)
			(layer "F.SilkS")
		)
		(fp_line
			(start -1.36144 0.174244)
			(end -0.880618 1.00711)
			(stroke
				(width 0.1524)
				(type default)
			)
			(layer "F.SilkS")
		)
		(fp_line
			(start -1.36144 1.00711)
			(end -1.842262 1.00711)
			(stroke
				(width 0.1524)
				(type default)
			)
			(layer "F.SilkS")
		)
		(fp_line
			(start -1.36144 1.918716)
			(end -1.36144 1.00711)
			(stroke
				(width 0.1524)
				(type default)
			)
			(layer "F.SilkS")
		)
		(fp_line
			(start -0.880618 0.174244)
			(end -1.842262 0.174244)
			(stroke
				(width 0.1524)
				(type default)
			)
			(layer "F.SilkS")
		)
		(fp_line
			(start -0.880618 1.00711)
			(end -1.36144 1.00711)
			(stroke
				(width 0.1524)
				(type default)
			)
			(layer "F.SilkS")
		)
		(fp_poly
			(pts
				(xy -0.5715 2.2098) (xy -0.5715 0.2032) (xy 0.5715 0.2032) (xy 0.5715 0.6985)
				(arc
					(start 0.726948 0.6985)
					(mid 1.29058 0.932279)
					(end 1.524 1.49606)
				)
				(arc
					(start 1.524 2.05994)
					(mid 1.2904 2.6239)
					(end 0.72644 2.8575)
				)
				(xy 0.5715 2.8575) (xy 0.5715 3.3528) (xy -0.5715 3.3528)
			)
			(stroke
				(width 0)
				(type default)
			)
			(fill no)
			(layer "F.CrtYd")
		)
		(fp_line
			(start -1.848612 0.973328)
			(end -1.36779 0.140462)
			(stroke
				(width 0.1)
				(type default)
			)
			(layer "F.Fab")
		)
		(fp_line
			(start -1.36779 0.140462)
			(end -1.36779 -0.98298)
			(stroke
				(width 0.1)
				(type default)
			)
			(layer "F.Fab")
		)
		(fp_line
			(start -1.36779 0.140462)
			(end -0.886968 0.973328)
			(stroke
				(width 0.1)
				(type default)
			)
			(layer "F.Fab")
		)
		(fp_line
			(start -1.36779 0.973328)
			(end -1.36779 1.884934)
			(stroke
				(width 0.1)
				(type default)
			)
			(layer "F.Fab")
		)
		(fp_line
			(start -0.886968 0.140462)
			(end -1.848612 0.140462)
			(stroke
				(width 0.1)
				(type default)
			)
			(layer "F.Fab")
		)
		(fp_line
			(start -0.886968 0.973328)
			(end -1.848612 0.973328)
			(stroke
				(width 0.1)
				(type default)
			)
			(layer "F.Fab")
		)
		(fp_line
			(start -0.5715 0.2032)
			(end 0.5715 0.2032)
			(stroke
				(width 0.1)
				(type default)
			)
			(layer "F.Fab")
		)
		(fp_line
			(start -0.5715 0.7112)
			(end 0.5715 0.7112)
			(stroke
				(width 0.1)
				(type default)
			)
			(layer "F.Fab")
		)
		(fp_line
			(start -0.5715 2.8448)
			(end 0.5715 2.8448)
			(stroke
				(width 0.1)
				(type default)
			)
			(layer "F.Fab")
		)
		(fp_line
			(start -0.5715 3.3528)
			(end -0.5715 0.2032)
			(stroke
				(width 0.1)
				(type default)
			)
			(layer "F.Fab")
		)
		(fp_line
			(start 0.5715 0.2032)
			(end 0.5715 3.3528)
			(stroke
				(width 0.1)
				(type default)
			)
			(layer "F.Fab")
		)
		(fp_line
			(start 0.5715 2.8575)
			(end 0.72644 2.8575)
			(stroke
				(width 0.1)
				(type default)
			)
			(layer "F.Fab")
		)
		(fp_line
			(start 0.5715 3.3528)
			(end -0.5715 3.3528)
			(stroke
				(width 0.1)
				(type default)
			)
			(layer "F.Fab")
		)
		(fp_line
			(start 0.72644 0.6985)
			(end 0.5715 0.6985)
			(stroke
				(width 0.1)
				(type default)
			)
			(layer "F.Fab")
		)
		(fp_line
			(start 1.524 2.05994)
			(end 1.524 1.49606)
			(stroke
				(width 0.1)
				(type default)
			)
			(layer "F.Fab")
		)
		(fp_arc
			(start 0.72644 0.6985)
			(mid 1.290388 0.932112)
			(end 1.524 1.49606)
			(stroke
				(width 0.1)
				(type default)
			)
			(layer "F.Fab")
		)
		(fp_arc
			(start 1.524 2.05994)
			(mid 1.290388 2.623888)
			(end 0.72644 2.8575)
			(stroke
				(width 0.1)
				(type default)
			)
			(layer "F.Fab")
		)
		(pad "1" smd rect
			(at 0 0)
			(size 1.524 1.524)
			(layers "F.Cu" "F.Mask" "F.Paste")
			(net "FP_LED_HDD_ACTIVITY_AND_N")
		)
		(pad "2" smd rect
			(at 0 3.556)
			(size 1.524 1.524)
			(layers "F.Cu" "F.Mask" "F.Paste")
			(net "FP_LED_HDD_ACTIVITY_AND_R_N")
		)
		(pad "3" smd rect
			(at -0.762 1.778)
			(size 0.889 0.889)
			(layers "F.Cu" "F.Mask" "F.Paste")
			(net "Net_6478")
		)
		(zone
			(layer "F.Cu")
			(hatch none 0.5)
			(connect_pads
				(clearance 0)
			)
			(min_thickness 0.25)
			(keepout
				(tracks allowed)
				(vias not_allowed)
				(pads allowed)
				(copperpour not_allowed)
				(footprints allowed)
			)
			(placement
				(enabled no)
				(sheetname "")
			)
			(fill
				(thermal_gap 0.5)
				(thermal_bridge_width 0.5)
				(island_removal_mode 0)
			)
			(polygon
				(pts
					(xy 500.4435 -149.0472) (xy 500.4435 -147.1168) (xy 499.3005 -147.1168) (xy 499.3005 -149.0472)
				)
			)
		)
	)
	(footprint ""
		(layer "F.Cu")
		(at 413.639 -21.971 180)
		(property "Reference" "R25W116"
			(at -0.8382 -0.67818 180)
			(unlocked yes)
			(layer "F.SilkS")
			(effects
				(font
					(size 0.4064 0.254)
					(thickness 0.1524)
				)
				(justify left)
			)
		)
		(property "Value" ""
			(at 0 0 180)
			(layer "F.Fab")
			(effects
				(font
					(size 1.27 1.27)
				)
			)
		)
		(duplicate_pad_numbers_are_jumpers no)
		(fp_poly
			(pts
				(xy -0.2794 -0.1016) (xy 0.2794 -0.1016) (xy 0.2794 0.9906) (xy -0.2794 0.9906)
			)
			(stroke
				(width 0)
				(type default)
			)
			(fill no)
			(layer "F.CrtYd")
		)
		(fp_line
			(start 0.2794 0.9906)
			(end 0.2794 -0.1016)
			(stroke
				(width 0.1)
				(type default)
			)
			(layer "F.Fab")
		)
		(fp_line
			(start 0.2794 -0.1016)
			(end -0.2794 -0.1016)
			(stroke
				(width 0.1)
				(type default)
			)
			(layer "F.Fab")
		)
		(fp_line
			(start -0.2794 0.9906)
			(end 0.2794 0.9906)
			(stroke
				(width 0.1)
				(type default)
			)
			(layer "F.Fab")
		)
		(fp_line
			(start -0.2794 -0.1016)
			(end -0.2794 0.9906)
			(stroke
				(width 0.1)
				(type default)
			)
			(layer "F.Fab")
		)
		(pad "1" smd rect
			(at 0 0 180)
			(size 0.508 0.508)
			(layers "F.Cu" "F.Mask" "F.Paste")
			(net "GND")
		)
		(pad "2" smd rect
			(at 0 0.889 180)
			(size 0.508 0.508)
			(layers "F.Cu" "F.Mask" "F.Paste")
			(net "UART_BMC_TXD5")
		)
		(zone
			(layer "F.Cu")
			(hatch none 0.5)
			(connect_pads
				(clearance 0)
			)
			(min_thickness 0.25)
			(keepout
				(tracks not_allowed)
				(vias allowed)
				(pads allowed)
				(copperpour not_allowed)
				(footprints allowed)
			)
			(placement
				(enabled no)
				(sheetname "")
			)
			(fill
				(thermal_gap 0.5)
				(thermal_bridge_width 0.5)
				(island_removal_mode 0)
			)
			(polygon
				(pts
					(xy 413.893 -22.606) (xy 413.385 -22.606) (xy 413.385 -22.225) (xy 413.893 -22.225)
				)
			)
		)
		(zone
			(layer "F.Cu")
			(hatch none 0.5)
			(connect_pads
				(clearance 0)
			)
			(min_thickness 0.25)
			(keepout
				(tracks allowed)
				(vias not_allowed)
				(pads allowed)
				(copperpour not_allowed)
				(footprints allowed)
			)
			(placement
				(enabled no)
				(sheetname "")
			)
			(fill
				(thermal_gap 0.5)
				(thermal_bridge_width 0.5)
				(island_removal_mode 0)
			)
			(polygon
				(pts
					(xy 413.893 -22.225) (xy 413.385 -22.225) (xy 413.385 -22.606) (xy 413.893 -22.606)
				)
			)
		)
	)
	(footprint ""
		(layer "F.Cu")
		(at 347.462094 -153.218642 -90)
		(property "Reference" "EU7A1"
			(at 3.410712 2.733294 0)
			(unlocked yes)
			(layer "F.SilkS")
			(effects
				(font
					(size 0.7874 0.5842)
					(thickness 0.1524)
				)
			)
		)
		(property "Value" ""
			(at 0 0 270)
			(layer "F.Fab")
			(effects
				(font
					(size 1.27 1.27)
				)
			)
		)
		(duplicate_pad_numbers_are_jumpers no)
		(fp_line
			(start -3.0099 3.429)
			(end -3.0099 -3.5052)
			(stroke
				(width 0.1524)
				(type default)
			)
			(layer "F.SilkS")
		)
		(fp_line
			(start 2.9718 3.429)
			(end -3.0099 3.429)
			(stroke
				(width 0.1524)
				(type default)
			)
			(layer "F.SilkS")
		)
		(fp_line
			(start -3.0099 -3.5052)
			(end 2.9718 -3.5052)
			(stroke
				(width 0.1524)
				(type default)
			)
			(layer "F.SilkS")
		)
		(fp_line
			(start 2.9718 -3.5052)
			(end 2.9718 3.429)
			(stroke
				(width 0.1524)
				(type default)
			)
			(layer "F.SilkS")
		)
		(fp_circle
			(center -3.057398 -2.678684)
			(end -3.057398 -2.805684)
			(stroke
				(width 0.254)
				(type default)
			)
			(fill no)
			(layer "F.SilkS")
		)
		(fp_poly
			(pts
				(xy -2.9972 -3.4925) (xy -2.9972 -2.6924) (xy -2.1971 -3.4925)
			)
			(stroke
				(width 0)
				(type default)
			)
			(fill yes)
			(layer "F.SilkS")
		)
		(fp_poly
			(pts
				(xy -2.549906 -3.050032) (xy -2.549906 3.050032) (xy 2.549906 3.050032) (xy 2.549906 -3.050032)
			)
			(stroke
				(width 0)
				(type default)
			)
			(fill no)
			(layer "F.CrtYd")
		)
		(fp_line
			(start -2.549906 3.050032)
			(end -2.549906 -3.050032)
			(stroke
				(width 0.1)
				(type default)
			)
			(layer "F.Fab")
		)
		(fp_line
			(start 2.549906 3.050032)
			(end -2.549906 3.050032)
			(stroke
				(width 0.1)
				(type default)
			)
			(layer "F.Fab")
		)
		(fp_line
			(start -2.549906 -3.050032)
			(end 2.549906 -3.050032)
			(stroke
				(width 0.1)
				(type default)
			)
			(layer "F.Fab")
		)
		(fp_line
			(start 2.549906 -3.050032)
			(end 2.549906 3.050032)
			(stroke
				(width 0.1)
				(type default)
			)
			(layer "F.Fab")
		)
		(fp_circle
			(center -3.057398 -2.678684)
			(end -3.057398 -2.805684)
			(stroke
				(width 0.254)
				(type default)
			)
			(fill no)
			(layer "F.Fab")
		)
		(pad "1" smd rect
			(at -2.39522 -2.279904 270)
			(size 0.7112 0.254)
			(layers "F.Cu" "F.Mask" "F.Paste")
			(net "PVDDQ_DEF")
		)
		(pad "2" smd rect
			(at -2.39522 -1.83007 270)
			(size 0.7112 0.254)
			(layers "F.Cu" "F.Mask" "F.Paste")
			(net "GND")
		)
		(pad "3" smd rect
			(at -2.39522 -1.379982 270)
			(size 0.7112 0.254)
			(layers "F.Cu" "F.Mask" "F.Paste")
			(net "VR_PVDDQ_DEF_PH1_VCIN")
		)
		(pad "4" smd rect
			(at -2.39522 -0.929894 270)
			(size 0.7112 0.254)
			(layers "F.Cu" "F.Mask" "F.Paste")
			(net "P5V_STBY")
		)
		(pad "5" smd rect
			(at -2.39522 -0.48006 270)
			(size 0.7112 0.254)
			(layers "F.Cu" "F.Mask" "F.Paste")
			(net "GND")
		)
		(pad "6" smd rect
			(at -2.39522 -0.029972 270)
			(size 0.7112 0.254)
			(layers "F.Cu" "F.Mask" "F.Paste")
			(net "TP_PVDDQ_DEF_PH1_GL_0")
		)
		(pad "7" smd custom
			(at 0.016764 1.145032 270)
			(size 0.53975 0.53975)
			(layers "F.Cu" "F.Mask" "F.Paste")
			(net "GND")
			(options
				(clearance outline)
				(anchor circle)
			)
			(primitives
				(gr_poly
					(pts
						(xy -2.7051 1.0795) (xy -2.7051 -0.3683) (xy -0.9271 -0.3683) (xy -0.9271 -1.0795) (xy 2.7051 -1.0795)
						(xy 2.7051 1.0795)
					)
					(width 0)
					(fill yes)
				)
			)
		)
		(pad "10" smd rect
			(at -0.008382 2.874772 270)
			(size 4.3434 0.6096)
			(layers "F.Cu" "F.Mask" "F.Paste")
			(net "VR_PVDDQ_DEF_PH1_SW")
		)
		(pad "25" smd rect
			(at 1.548384 -1.283208 270)
			(size 2.3368 2.0066)
			(layers "F.Cu" "F.Mask" "F.Paste")
			(net "VR_FET_SW_P12V_STBY_PVDDQ_DEF")
		)
		(pad "30" smd rect
			(at 2.050034 -2.895092 270)
			(size 0.254 0.7112)
			(layers "F.Cu" "F.Mask" "F.Paste")
			(net "VR_FET_SW_P12V_STBY_PVDDQ_DEF")
		)
		(pad "31" smd rect
			(at 1.599946 -2.895092 270)
			(size 0.254 0.7112)
			(layers "F.Cu" "F.Mask" "F.Paste")
			(net "Net_370")
		)
		(pad "32" smd rect
			(at 1.150112 -2.895092 270)
			(size 0.254 0.7112)
			(layers "F.Cu" "F.Mask" "F.Paste")
			(net "VR_PVDDQ_DEF_PH1_PHASE")
		)
		(pad "33" smd rect
			(at 0.700024 -2.895092 270)
			(size 0.254 0.7112)
			(layers "F.Cu" "F.Mask" "F.Paste")
			(net "VR_PVDDQ_DEF_PH1_BOOT_R")
		)
		(pad "34" smd rect
			(at 0.249936 -2.895092 270)
			(size 0.254 0.7112)
			(layers "F.Cu" "F.Mask" "F.Paste")
			(net "VR_PVDDQ_DEF_PWM1")
		)
		(pad "35" smd rect
			(at -0.199898 -2.895092 270)
			(size 0.254 0.7112)
			(layers "F.Cu" "F.Mask" "F.Paste")
			(net "P5V_STBY")
		)
		(pad "36" smd rect
			(at -0.649986 -2.895092 270)
			(size 0.254 0.7112)
			(layers "F.Cu" "F.Mask" "F.Paste")
			(net "A_TSENSE_PVDDQ_DEF")
		)
		(pad "37" smd rect
			(at -1.100074 -2.895092 270)
			(size 0.254 0.7112)
			(layers "F.Cu" "F.Mask" "F.Paste")
			(net "VR_PVDDQ_DEF_PH1_OCSET")
		)
		(pad "38" smd rect
			(at -1.549908 -2.895092 270)
			(size 0.254 0.7112)
			(layers "F.Cu" "F.Mask" "F.Paste")
			(net "ISENSE_PVDDQ_DEF_PH1_IMON")
		)
		(pad "39" smd rect
			(at -1.999996 -2.895092 270)
			(size 0.254 0.7112)
			(layers "F.Cu" "F.Mask" "F.Paste")
			(net "VR_PVDDQ_DEF_AIREF1")
		)
		(pad "40" smd rect
			(at -0.871728 -1.283208 270)
			(size 1.8034 2.0066)
			(layers "F.Cu" "F.Mask" "F.Paste")
			(net "GND")
		)
		(pad "41" smd rect
			(at -1.533906 0.247904 270)
			(size 0.508 0.3556)
			(layers "F.Cu" "F.Mask" "F.Paste")
			(net "TP_PVDDQ_DEF_PH1_GL_1")
		)
	)
	(footprint ""
		(layer "F.Cu")
		(at 490.2835 -145.527268 -90)
		(property "Reference" "C1T56"
			(at 0 0 270)
			(layer "F.SilkS")
			(hide yes)
			(effects
				(font
					(size 1.27 1.27)
				)
			)
		)
		(property "Value" ""
			(at 0 0 270)
			(layer "F.Fab")
			(effects
				(font
					(size 1.27 1.27)
				)
			)
		)
		(duplicate_pad_numbers_are_jumpers no)
		(fp_poly
			(pts
				(xy 0.3048 -0.1016) (xy 0.3048 0.9906) (xy -0.3048 0.9906) (xy -0.3048 -0.1016)
			)
			(stroke
				(width 0)
				(type default)
			)
			(fill no)
			(layer "F.CrtYd")
		)
		(fp_line
			(start -0.3048 0.9906)
			(end 0.3048 0.9906)
			(stroke
				(width 0.1)
				(type default)
			)
			(layer "F.Fab")
		)
		(fp_line
			(start 0.3048 0.9906)
			(end 0.3048 -0.1016)
			(stroke
				(width 0.1)
				(type default)
			)
			(layer "F.Fab")
		)
		(fp_line
			(start -0.3048 -0.1016)
			(end -0.3048 0.9906)
			(stroke
				(width 0.1)
				(type default)
			)
			(layer "F.Fab")
		)
		(fp_line
			(start 0.3048 -0.1016)
			(end -0.3048 -0.1016)
			(stroke
				(width 0.1)
				(type default)
			)
			(layer "F.Fab")
		)
		(pad "1" smd rect
			(at 0 0 270)
			(size 0.508 0.508)
			(layers "F.Cu" "F.Mask" "F.Paste")
			(net "P3V3_STBY")
		)
		(pad "2" smd rect
			(at 0 0.889 270)
			(size 0.508 0.508)
			(layers "F.Cu" "F.Mask" "F.Paste")
			(net "GND")
		)
		(zone
			(layer "F.Cu")
			(hatch none 0.5)
			(connect_pads
				(clearance 0)
			)
			(min_thickness 0.25)
			(keepout
				(tracks not_allowed)
				(vias allowed)
				(pads allowed)
				(copperpour not_allowed)
				(footprints allowed)
			)
			(placement
				(enabled no)
				(sheetname "")
			)
			(fill
				(thermal_gap 0.5)
				(thermal_bridge_width 0.5)
				(island_removal_mode 0)
			)
			(polygon
				(pts
					(xy 489.6485 -145.781268) (xy 489.6485 -145.273268) (xy 490.0295 -145.273268) (xy 490.0295 -145.781268)
				)
			)
		)
		(zone
			(layer "F.Cu")
			(hatch none 0.5)
			(connect_pads
				(clearance 0)
			)
			(min_thickness 0.25)
			(keepout
				(tracks allowed)
				(vias not_allowed)
				(pads allowed)
				(copperpour not_allowed)
				(footprints allowed)
			)
			(placement
				(enabled no)
				(sheetname "")
			)
			(fill
				(thermal_gap 0.5)
				(thermal_bridge_width 0.5)
				(island_removal_mode 0)
			)
			(polygon
				(pts
					(xy 490.0295 -145.781268) (xy 490.0295 -145.273268) (xy 489.6485 -145.273268) (xy 489.6485 -145.781268)
				)
			)
		)
	)
	(footprint ""
		(layer "F.Cu")
		(at 275.463 -69.977)
		(property "Reference" "R5D4"
			(at 0 0 0)
			(layer "F.SilkS")
			(hide yes)
			(effects
				(font
					(size 1.27 1.27)
				)
			)
		)
		(property "Value" ""
			(at 0 0 0)
			(layer "F.Fab")
			(effects
				(font
					(size 1.27 1.27)
				)
			)
		)
		(duplicate_pad_numbers_are_jumpers no)
		(fp_poly
			(pts
				(xy -0.2794 -0.1016) (xy 0.2794 -0.1016) (xy 0.2794 0.9906) (xy -0.2794 0.9906)
			)
			(stroke
				(width 0)
				(type default)
			)
			(fill no)
			(layer "F.CrtYd")
		)
		(fp_line
			(start -0.2794 -0.1016)
			(end -0.2794 0.9906)
			(stroke
				(width 0.1)
				(type default)
			)
			(layer "F.Fab")
		)
		(fp_line
			(start -0.2794 0.9906)
			(end 0.2794 0.9906)
			(stroke
				(width 0.1)
				(type default)
			)
			(layer "F.Fab")
		)
		(fp_line
			(start 0.2794 -0.1016)
			(end -0.2794 -0.1016)
			(stroke
				(width 0.1)
				(type default)
			)
			(layer "F.Fab")
		)
		(fp_line
			(start 0.2794 0.9906)
			(end 0.2794 -0.1016)
			(stroke
				(width 0.1)
				(type default)
			)
			(layer "F.Fab")
		)
		(pad "1" smd rect
			(at 0 0)
			(size 0.508 0.508)
			(layers "F.Cu" "F.Mask" "F.Paste")
			(net "PVCCIO_CPU0")
		)
		(pad "2" smd rect
			(at 0 0.889)
			(size 0.508 0.508)
			(layers "F.Cu" "F.Mask" "F.Paste")
			(net "PU_CPU0_TXT_AGENT")
		)
		(zone
			(layer "F.Cu")
			(hatch none 0.5)
			(connect_pads
				(clearance 0)
			)
			(min_thickness 0.25)
			(keepout
				(tracks allowed)
				(vias not_allowed)
				(pads allowed)
				(copperpour not_allowed)
				(footprints allowed)
			)
			(placement
				(enabled no)
				(sheetname "")
			)
			(fill
				(thermal_gap 0.5)
				(thermal_bridge_width 0.5)
				(island_removal_mode 0)
			)
			(polygon
				(pts
					(xy 275.209 -69.723) (xy 275.717 -69.723) (xy 275.717 -69.342) (xy 275.209 -69.342)
				)
			)
		)
		(zone
			(layer "F.Cu")
			(hatch none 0.5)
			(connect_pads
				(clearance 0)
			)
			(min_thickness 0.25)
			(keepout
				(tracks not_allowed)
				(vias allowed)
				(pads allowed)
				(copperpour not_allowed)
				(footprints allowed)
			)
			(placement
				(enabled no)
				(sheetname "")
			)
			(fill
				(thermal_gap 0.5)
				(thermal_bridge_width 0.5)
				(island_removal_mode 0)
			)
			(polygon
				(pts
					(xy 275.209 -69.342) (xy 275.717 -69.342) (xy 275.717 -69.723) (xy 275.209 -69.723)
				)
			)
		)
	)
)
